# S9S_MB_2U (Grand Teton) — schematic netlist excerpt (pin names and nets, part order shuffled) for the footprints in the layout excerpt that follows; sources: Cadence DE-HDL packaged netlist, KiCad conversion of 03242023_DA0F0TMBIJ0_F0T_Motherboard_J_brd_V01_OCP.brd

U200  LTC4307CMS8  IC  pkg MSOP8  page 234
  ENABLE  = SMB_BMC_GPU_EN_R3
  SCL_OUT  = SMB_2_BMC_GPU_BUF_R_SCL
  SCL_IN  = SMB_2_BMC_GPU_R_SCL
  GND  = GND
  READY  = NC
  SDA_IN  = SMB_2_BMC_GPU_R_SDA
  SDA_OUT  = SMB_2_BMC_GPU_BUF_R_SDA
  VCC  = P3V3_AUX

R4739  Q_RES  4.7K 5% CHIP  pkg 0402LF  page 144 : A = P3V3_AUX ; B = PRSNT_CABLE_SWB_B1

(kicad_pcb
	(version 20260206)
	(generator "pcbnew")
	(generator_version "10.0")
	(general
		(thickness 1.6)
		(legacy_teardrops no)
	)
	(paper "A4")
	(title_block
		(title "03242023_DA0F0TMBIJ0_F0T_Motherboard_J_brd_V01_OCP.brd")
		(comment 1 "Grand Teton / footprints 3490-3491 of 6105")
	)
	(layers
		(0 "F.Cu" signal "TOP")
		(4 "In1.Cu" signal "GND")
		(6 "In2.Cu" signal "IN1")
		(8 "In3.Cu" signal "GND1")
		(10 "In4.Cu" signal "IN2")
		(12 "In5.Cu" signal "GND2")
		(14 "In6.Cu" signal "IN3")
		(16 "In7.Cu" signal "GND3")
		(18 "In8.Cu" signal "VCC")
		(20 "In9.Cu" signal "VCC1")
		(22 "In10.Cu" signal "GND4")
		(24 "In11.Cu" signal "IN4")
		(26 "In12.Cu" signal "GND5")
		(28 "In13.Cu" signal "IN5")
		(30 "In14.Cu" signal "GND6")
		(32 "In15.Cu" signal "IN6")
		(34 "In16.Cu" signal "GND7")
		(2 "B.Cu" signal "BOTTOM")
		(9 "F.Adhes" user "F.Adhesive")
		(11 "B.Adhes" user "B.Adhesive")
		(13 "F.Paste" user "Package Geometry/Pastemask Top")
		(15 "B.Paste" user "Package Geometry/Pastemask Bottom")
		(5 "F.SilkS" user "Ref Des/Silkscreen Top")
		(7 "B.SilkS" user "Ref Des/Silkscreen Bottom")
		(1 "F.Mask" user "Board Geometry/Soldermask Top")
		(3 "B.Mask" user "Board Geometry/Soldermask Bottom")
		(17 "Dwgs.User" user "User.Drawings")
		(19 "Cmts.User" user "User.Comments")
		(21 "Eco1.User" user "User.Eco1")
		(23 "Eco2.User" user "User.Eco2")
		(25 "Edge.Cuts" user "Board Geometry/Outline")
		(27 "Margin" user)
		(31 "F.CrtYd" user "Package Geometry/Place Bound Top")
		(29 "B.CrtYd" user "Package Geometry/Place Bound Bottom")
		(35 "F.Fab" user "Ref Des/Assembly Top")
		(33 "B.Fab" user "Ref Des/Assembly Bottom")
	)
	(footprint ""
		(layer "F.Cu")
		(at 369.81511 -409.6512)
		(property "Reference" "R4739"
			(at 0 0 0)
			(layer "F.SilkS")
			(hide yes)
			(effects
				(font
					(size 1.27 1.27)
				)
			)
		)
		(property "Value" ""
			(at 0 0 0)
			(layer "F.Fab")
			(effects
				(font
					(size 1.27 1.27)
				)
			)
		)
		(duplicate_pad_numbers_are_jumpers no)
		(fp_line
			(start -0.7874 -0.4064)
			(end 0.7874 -0.4064)
			(stroke
				(width 0.1524)
				(type default)
			)
			(layer "F.SilkS")
		)
		(fp_line
			(start -0.7874 0.4064)
			(end -0.7874 -0.4064)
			(stroke
				(width 0.1524)
				(type default)
			)
			(layer "F.SilkS")
		)
		(fp_line
			(start 0.7874 -0.4064)
			(end 0.7874 0.4064)
			(stroke
				(width 0.1524)
				(type default)
			)
			(layer "F.SilkS")
		)
		(fp_line
			(start 0.7874 0.4064)
			(end -0.7874 0.4064)
			(stroke
				(width 0.1524)
				(type default)
			)
			(layer "F.SilkS")
		)
		(fp_line
			(start -0.67945 -0.305054)
			(end -0.12065 -0.305054)
			(stroke
				(width 0.1)
				(type default)
			)
			(layer "F.Fab")
		)
		(fp_line
			(start -0.67945 0.3048)
			(end -0.67945 -0.305054)
			(stroke
				(width 0.1)
				(type default)
			)
			(layer "F.Fab")
		)
		(fp_line
			(start -0.12065 -0.305054)
			(end -0.12065 -0.2794)
			(stroke
				(width 0.1)
				(type default)
			)
			(layer "F.Fab")
		)
		(fp_line
			(start -0.12065 -0.2794)
			(end 0.12065 -0.2794)
			(stroke
				(width 0.1)
				(type default)
			)
			(layer "F.Fab")
		)
		(fp_line
			(start -0.12065 0.2794)
			(end -0.12065 0.3048)
			(stroke
				(width 0.1)
				(type default)
			)
			(layer "F.Fab")
		)
		(fp_line
			(start -0.12065 0.3048)
			(end -0.67945 0.3048)
			(stroke
				(width 0.1)
				(type default)
			)
			(layer "F.Fab")
		)
		(fp_line
			(start 0.120396 0.2794)
			(end -0.12065 0.2794)
			(stroke
				(width 0.1)
				(type default)
			)
			(layer "F.Fab")
		)
		(fp_line
			(start 0.120396 0.3048)
			(end 0.120396 0.2794)
			(stroke
				(width 0.1)
				(type default)
			)
			(layer "F.Fab")
		)
		(fp_line
			(start 0.12065 -0.3048)
			(end 0.67945 -0.3048)
			(stroke
				(width 0.1)
				(type default)
			)
			(layer "F.Fab")
		)
		(fp_line
			(start 0.12065 -0.2794)
			(end 0.12065 -0.3048)
			(stroke
				(width 0.1)
				(type default)
			)
			(layer "F.Fab")
		)
		(fp_line
			(start 0.67945 -0.3048)
			(end 0.67945 0.3048)
			(stroke
				(width 0.1)
				(type default)
			)
			(layer "F.Fab")
		)
		(fp_line
			(start 0.67945 0.3048)
			(end 0.120396 0.3048)
			(stroke
				(width 0.1)
				(type default)
			)
			(layer "F.Fab")
		)
		(pad "1" smd circle
			(at -0.40005 0)
			(size 0 0)
			(layers "F.Cu" "F.Mask" "F.Paste")
			(net "P3V3_AUX")
		)
		(pad "2" smd circle
			(at 0.40005 0)
			(size 0 0)
			(layers "F.Cu" "F.Mask" "F.Paste")
			(net "PRSNT_CABLE_SWB_B1")
		)
	)
	(footprint ""
		(layer "F.Cu")
		(at 39.032688 -439.198512 180)
		(property "Reference" "U200"
			(at 0.153416 -2.198878 0)
			(unlocked yes)
			(layer "F.SilkS")
			(effects
				(font
					(size 0.7874 0.5842)
					(thickness 0.1524)
				)
				(justify left)
			)
		)
		(property "Value" ""
			(at 0 0 180)
			(layer "F.Fab")
			(effects
				(font
					(size 1.27 1.27)
				)
			)
		)
		(duplicate_pad_numbers_are_jumpers no)
		(fp_line
			(start 1.3716 1.524)
			(end -1.3716 1.524)
			(stroke
				(width 0.1524)
				(type default)
			)
			(layer "F.SilkS")
		)
		(fp_line
			(start 1.3716 -1.524)
			(end 1.3716 1.524)
			(stroke
				(width 0.1524)
				(type default)
			)
			(layer "F.SilkS")
		)
		(fp_line
			(start 0.508 -1.524)
			(end 1.3716 -1.524)
			(stroke
				(width 0.1524)
				(type default)
			)
			(layer "F.SilkS")
		)
		(fp_line
			(start 0 -1.016)
			(end 0.508 -1.524)
			(stroke
				(width 0.1524)
				(type default)
			)
			(layer "F.SilkS")
		)
		(fp_line
			(start -0.508 -1.524)
			(end 0 -1.016)
			(stroke
				(width 0.1524)
				(type default)
			)
			(layer "F.SilkS")
		)
		(fp_line
			(start -1.3716 1.524)
			(end -1.3716 -1.524)
			(stroke
				(width 0.1524)
				(type default)
			)
			(layer "F.SilkS")
		)
		(fp_line
			(start -1.3716 -1.524)
			(end -0.508 -1.524)
			(stroke
				(width 0.1524)
				(type default)
			)
			(layer "F.SilkS")
		)
		(fp_poly
			(pts
				(xy -3.70332 -1.270508) (xy -3.1496 -0.94234) (xy -3.70332 -0.645668)
			)
			(stroke
				(width 0)
				(type default)
			)
			(fill yes)
			(layer "F.SilkS")
		)
		(fp_line
			(start 2.54 1.0668)
			(end 1.5494 1.0668)
			(stroke
				(width 0.1)
				(type default)
			)
			(layer "F.Fab")
		)
		(fp_line
			(start 2.54 -1.0668)
			(end 2.54 1.0668)
			(stroke
				(width 0.1)
				(type default)
			)
			(layer "F.Fab")
		)
		(fp_line
			(start 1.5494 1.524)
			(end -1.5494 1.524)
			(stroke
				(width 0.1)
				(type default)
			)
			(layer "F.Fab")
		)
		(fp_line
			(start 1.5494 1.0668)
			(end 1.5494 1.524)
			(stroke
				(width 0.1)
				(type default)
			)
			(layer "F.Fab")
		)
		(fp_line
			(start 1.5494 -1.0668)
			(end 2.54 -1.0668)
			(stroke
				(width 0.1)
				(type default)
			)
			(layer "F.Fab")
		)
		(fp_line
			(start 1.5494 -1.0668)
			(end 1.5494 1.0668)
			(stroke
				(width 0.1)
				(type default)
			)
			(layer "F.Fab")
		)
		(fp_line
			(start 1.5494 -1.524)
			(end 1.5494 -1.0668)
			(stroke
				(width 0.1)
				(type default)
			)
			(layer "F.Fab")
		)
		(fp_line
			(start -1.5494 1.524)
			(end -1.5494 1.0668)
			(stroke
				(width 0.1)
				(type default)
			)
			(layer "F.Fab")
		)
		(fp_line
			(start -1.5494 1.0668)
			(end -1.5494 -1.0668)
			(stroke
				(width 0.1)
				(type default)
			)
			(layer "F.Fab")
		)
		(fp_line
			(start -1.5494 1.0668)
			(end -2.54 1.0668)
			(stroke
				(width 0.1)
				(type default)
			)
			(layer "F.Fab")
		)
		(fp_line
			(start -1.5494 -1.0668)
			(end -1.5494 -1.524)
			(stroke
				(width 0.1)
				(type default)
			)
			(layer "F.Fab")
		)
		(fp_line
			(start -1.5494 -1.524)
			(end 1.5494 -1.524)
			(stroke
				(width 0.1)
				(type default)
			)
			(layer "F.Fab")
		)
		(fp_line
			(start -2.54 1.0668)
			(end -2.54 -1.0668)
			(stroke
				(width 0.1)
				(type default)
			)
			(layer "F.Fab")
		)
		(fp_line
			(start -2.54 -1.0668)
			(end -1.5494 -1.0668)
			(stroke
				(width 0.1)
				(type default)
			)
			(layer "F.Fab")
		)
		(fp_poly
			(pts
				(xy -3.60172 -0.719328) (xy -3.60172 -1.344168) (xy -3.048 -1.016)
			)
			(stroke
				(width 0)
				(type default)
			)
			(fill yes)
			(layer "F.Fab")
		)
		(pad "1" smd rect
			(at -2.232406 -0.975106 90)
			(size 0.3556 1.4224)
			(layers "F.Cu" "F.Mask" "F.Paste")
			(net "SMB_BMC_GPU_EN_R3")
		)
		(pad "2" smd rect
			(at -2.232406 -0.32512 90)
			(size 0.3556 1.4224)
			(layers "F.Cu" "F.Mask" "F.Paste")
			(net "SMB_2_BMC_GPU_BUF_R_SCL")
		)
		(pad "3" smd rect
			(at -2.232406 0.32512 90)
			(size 0.3556 1.4224)
			(layers "F.Cu" "F.Mask" "F.Paste")
			(net "SMB_2_BMC_GPU_R_SCL")
		)
		(pad "4" smd rect
			(at -2.232406 0.975106 90)
			(size 0.3556 1.4224)
			(layers "F.Cu" "F.Mask" "F.Paste")
			(net "GND")
		)
		(pad "5" smd rect
			(at 2.232406 0.975106 90)
			(size 0.3556 1.4224)
			(layers "F.Cu" "F.Mask" "F.Paste")
			(net "Net_1937")
		)
		(pad "6" smd rect
			(at 2.232406 0.32512 90)
			(size 0.3556 1.4224)
			(layers "F.Cu" "F.Mask" "F.Paste")
			(net "SMB_2_BMC_GPU_R_SDA")
		)
		(pad "7" smd rect
			(at 2.232406 -0.32512 90)
			(size 0.3556 1.4224)
			(layers "F.Cu" "F.Mask" "F.Paste")
			(net "SMB_2_BMC_GPU_BUF_R_SDA")
		)
		(pad "8" smd rect
			(at 2.232406 -0.975106 90)
			(size 0.3556 1.4224)
			(layers "F.Cu" "F.Mask" "F.Paste")
			(net "P3V3_AUX")
		)
	)
)
